(kicad_pcb
	(version 20241229)
	(generator "pcbnew")
	(generator_version "9.0")
	(general
		(thickness 1.61)
		(legacy_teardrops no)
	)
	(paper "A3")
	(title_block
		(title "RDIMM DDR5 Tester")
		(date "2026-05-21")
		(rev "2.2.0")
		(company "Antmicro")
		(comment 9 "footprints 548-552 of 796")
	)
	(layers
		(0 "F.Cu" signal)
		(4 "In1.Cu" power)
		(6 "In2.Cu" mixed)
		(8 "In3.Cu" power)
		(10 "In4.Cu" mixed)
		(12 "In5.Cu" power)
		(14 "In6.Cu" mixed)
		(16 "In7.Cu" power)
		(18 "In8.Cu" power)
		(20 "In9.Cu" mixed)
		(22 "In10.Cu" power)
		(2 "B.Cu" signal)
		(9 "F.Adhes" user "F.Adhesive")
		(11 "B.Adhes" user "B.Adhesive")
		(13 "F.Paste" user)
		(15 "B.Paste" user)
		(5 "F.SilkS" user "F.Silkscreen")
		(7 "B.SilkS" user "B.Silkscreen")
		(1 "F.Mask" user)
		(3 "B.Mask" user)
		(17 "Dwgs.User" user "User.Drawings")
		(19 "Cmts.User" user "User.Comments")
		(21 "Eco1.User" user "User.Eco1")
		(23 "Eco2.User" user "User.Eco2")
		(25 "Edge.Cuts" user)
		(27 "Margin" user)
		(31 "F.CrtYd" user "F.Courtyard")
		(29 "B.CrtYd" user "B.Courtyard")
		(35 "F.Fab" user)
		(33 "B.Fab" user)
	)
	(footprint "antmicro-footprints:C_0402_1005Metric_EIA"
		(layer "B.Cu")
		(at 192 158.5 90)
		(descr "Capacitor SMD 0402 (1005 Metric), square (rectangular) end terminal, IPC_7351 nominal, (Body size source: IPC-SM-782 page 76, https://www.pcb-3d.com/wordpress/wp-content/uploads/ipc-sm-782a_amendment_1_and_2.pdf)")
		(tags "capacitor 0402")
		(property "Reference" "C79"
			(at 9.525 -30.65 90)
			(layer "B.SilkS")
			(effects
				(font
					(size 0.7 0.7)
					(thickness 0.15)
				)
				(justify right bottom mirror)
			)
		)
		(property "Value" "C_1u_25V_0402"
			(at 0 -1.169 90)
			(layer "B.Fab")
			(effects
				(font
					(size 0.7 0.7)
					(thickness 0.15)
				)
				(justify right bottom mirror)
			)
		)
		(property "Datasheet" "https://www.murata.com/products/productdetail?partno=GRM155R61E105KE11%23"
			(at 0 0 90)
			(layer "F.Fab")
			(hide yes)
			(effects
				(font
					(size 1.27 1.27)
					(thickness 0.15)
				)
			)
		)
		(property "MPN" "GRM155R61E105KE11J"
			(at 0 0 90)
			(unlocked yes)
			(layer "B.Fab")
			(hide yes)
			(effects
				(font
					(size 1 1)
					(thickness 0.15)
				)
				(justify mirror)
			)
		)
		(property "Manufacturer" "Murata"
			(at 0 0 90)
			(unlocked yes)
			(layer "B.Fab")
			(hide yes)
			(effects
				(font
					(size 1 1)
					(thickness 0.15)
				)
				(justify mirror)
			)
		)
		(property "License" "Apache-2.0"
			(at 0 0 90)
			(unlocked yes)
			(layer "B.Fab")
			(hide yes)
			(effects
				(font
					(size 1 1)
					(thickness 0.15)
				)
				(justify mirror)
			)
		)
		(property "Author" "Antmicro"
			(at 0 0 90)
			(unlocked yes)
			(layer "B.Fab")
			(hide yes)
			(effects
				(font
					(size 1 1)
					(thickness 0.15)
				)
				(justify mirror)
			)
		)
		(property "Val" "1u"
			(at 0 0 90)
			(unlocked yes)
			(layer "B.Fab")
			(hide yes)
			(effects
				(font
					(size 1 1)
					(thickness 0.15)
				)
				(justify mirror)
			)
		)
		(property "Voltage" "25V"
			(at 0 0 90)
			(unlocked yes)
			(layer "B.Fab")
			(hide yes)
			(effects
				(font
					(size 1 1)
					(thickness 0.15)
				)
				(justify mirror)
			)
		)
		(property "Dielectric" "X5R"
			(at 0 0 90)
			(unlocked yes)
			(layer "B.Fab")
			(hide yes)
			(effects
				(font
					(size 1 1)
					(thickness 0.15)
				)
				(justify mirror)
			)
		)
		(sheetname "/FPGA power/")
		(sheetfile "fpga-power.kicad_sch")
		(attr smd)
		(fp_rect
			(start -0.95 0.45)
			(end 0.95 -0.45)
			(stroke
				(width 0.05)
				(type default)
			)
			(fill no)
			(layer "B.CrtYd")
		)
		(fp_line
			(start 0.498 -0.248)
			(end -0.5 -0.248)
			(stroke
				(width 0.15)
				(type solid)
			)
			(layer "B.Fab")
		)
		(fp_line
			(start -0.5 -0.248)
			(end -0.5 0.25)
			(stroke
				(width 0.15)
				(type solid)
			)
			(layer "B.Fab")
		)
		(fp_line
			(start 0.498 0.25)
			(end 0.498 -0.248)
			(stroke
				(width 0.15)
				(type solid)
			)
			(layer "B.Fab")
		)
		(fp_line
			(start -0.5 0.25)
			(end 0.498 0.25)
			(stroke
				(width 0.15)
				(type solid)
			)
			(layer "B.Fab")
		)
		(fp_text user "${REFERENCE}"
			(at -0.9656 -3.169 270)
			(layer "B.Fab")
			(effects
				(font
					(size 0.7 0.7)
					(thickness 0.15)
				)
				(justify left bottom mirror)
			)
		)
		(fp_text user "License: Apache-2.0"
			(at -0.9656 -4.369 270)
			(layer "B.Fab")
			(effects
				(font
					(size 0.7 0.7)
					(thickness 0.15)
				)
				(justify left bottom mirror)
			)
		)
		(fp_text user "Author: Antmicro"
			(at -0.9656 -5.569 270)
			(layer "B.Fab")
			(effects
				(font
					(size 0.7 0.7)
					(thickness 0.15)
				)
				(justify left bottom mirror)
			)
		)
		(pad "1" smd roundrect
			(at -0.5 0)
			(size 0.6 0.6)
			(layers "B.Cu" "B.Mask" "B.Paste")
			(roundrect_rratio 0.25)
			(net 1 "GND")
			(pintype "passive")
		)
		(pad "2" smd roundrect
			(at 0.498 0 90)
			(size 0.6 0.6)
			(layers "B.Cu" "B.Mask" "B.Paste")
			(roundrect_rratio 0.25)
			(net 553 "+0V85")
			(pintype "passive")
		)
	)
	(footprint "antmicro-footprints:R_0402_1005Metric"
		(layer "B.Cu")
		(at 238.439499 166.235)
		(descr "Resistor SMD 0402")
		(tags "resistor SMD 0402")
		(property "Reference" "R135"
			(at 1.173001 0.475 0)
			(layer "B.SilkS")
			(effects
				(font
					(size 0.7 0.7)
					(thickness 0.15)
				)
				(justify right bottom mirror)
			)
		)
		(property "Value" "R_47k_0402"
			(at -1.011843 -1.772047 0)
			(layer "B.Fab")
			(effects
				(font
					(size 0.7 0.7)
					(thickness 0.15)
				)
				(justify right bottom mirror)
			)
		)
		(property "Datasheet" "https://www.bourns.com/docs/product-datasheets/cr.pdf"
			(at 0 0 0)
			(layer "F.Fab")
			(hide yes)
			(effects
				(font
					(size 1.27 1.27)
					(thickness 0.15)
				)
			)
		)
		(property "Manufacturer" "Bourns"
			(at 0 0 0)
			(unlocked yes)
			(layer "B.Fab")
			(hide yes)
			(effects
				(font
					(size 1 1)
					(thickness 0.15)
				)
				(justify mirror)
			)
		)
		(property "MPN" "CR0402-FX-4702GLF"
			(at 0 0 0)
			(unlocked yes)
			(layer "B.Fab")
			(hide yes)
			(effects
				(font
					(size 1 1)
					(thickness 0.15)
				)
				(justify mirror)
			)
		)
		(property "Val" "47k"
			(at 0 0 0)
			(unlocked yes)
			(layer "B.Fab")
			(hide yes)
			(effects
				(font
					(size 1 1)
					(thickness 0.15)
				)
				(justify mirror)
			)
		)
		(property "License" "Apache-2.0"
			(at 0 0 0)
			(unlocked yes)
			(layer "B.Fab")
			(hide yes)
			(effects
				(font
					(size 1 1)
					(thickness 0.15)
				)
				(justify mirror)
			)
		)
		(property "Author" "Antmicro"
			(at 0 0 0)
			(unlocked yes)
			(layer "B.Fab")
			(hide yes)
			(effects
				(font
					(size 1 1)
					(thickness 0.15)
				)
				(justify mirror)
			)
		)
		(property "Tolerance" "1%"
			(at 0 0 0)
			(unlocked yes)
			(layer "B.Fab")
			(hide yes)
			(effects
				(font
					(size 1 1)
					(thickness 0.15)
				)
				(justify mirror)
			)
		)
		(sheetname "/Supply/")
		(sheetfile "supply.kicad_sch")
		(attr smd)
		(fp_rect
			(start -0.925 0.47)
			(end 0.925 -0.47)
			(stroke
				(width 0.05)
				(type default)
			)
			(fill no)
			(layer "B.CrtYd")
		)
		(fp_rect
			(start -0.5 0.25)
			(end 0.5 -0.25)
			(stroke
				(width 0.15)
				(type solid)
			)
			(fill no)
			(layer "B.Fab")
		)
		(fp_text user "Author: Antmicro"
			(at -0.95 -4.169 180)
			(layer "B.Fab")
			(effects
				(font
					(size 0.7 0.7)
					(thickness 0.15)
				)
				(justify left bottom mirror)
			)
		)
		(fp_text user "License: Apache-2.0"
			(at -0.95 -5.169 180)
			(layer "B.Fab")
			(effects
				(font
					(size 0.7 0.7)
					(thickness 0.15)
				)
				(justify left bottom mirror)
			)
		)
		(fp_text user "${REFERENCE}"
			(at -0.95 -3.168 180)
			(layer "B.Fab")
			(effects
				(font
					(size 0.7 0.7)
					(thickness 0.15)
				)
				(justify left bottom mirror)
			)
		)
		(pad "1" smd roundrect
			(at -0.48 0)
			(size 0.59 0.64)
			(layers "B.Cu" "B.Mask" "B.Paste")
			(roundrect_rratio 0.25)
			(net 183 "POWER")
			(pintype "passive")
		)
		(pad "2" smd roundrect
			(at 0.48 0)
			(size 0.59 0.64)
			(layers "B.Cu" "B.Mask" "B.Paste")
			(roundrect_rratio 0.25)
			(net 38 "+3V3_AON")
			(pintype "passive")
		)
	)
	(footprint "antmicro-footprints:SC70-3"
		(layer "B.Cu")
		(at 115.17 166.86 90)
		(property "Reference" "Q19"
			(at -1.24 2.23 90)
			(layer "B.SilkS")
			(effects
				(font
					(size 0.7 0.7)
					(thickness 0.15)
				)
				(justify right bottom mirror)
			)
		)
		(property "Value" "BSS138PW"
			(at 0 -2.3 90)
			(layer "B.Fab")
			(effects
				(font
					(size 0.7 0.7)
					(thickness 0.15)
				)
				(justify right bottom mirror)
			)
		)
		(property "Datasheet" "https://assets.nexperia.com/documents/data-sheet/BSS138PW.pdf"
			(at 0 0 90)
			(layer "F.Fab")
			(hide yes)
			(effects
				(font
					(size 1.27 1.27)
					(thickness 0.15)
				)
			)
		)
		(property "MPN" "BSS138PW"
			(at 0 0 90)
			(unlocked yes)
			(layer "B.Fab")
			(hide yes)
			(effects
				(font
					(size 1 1)
					(thickness 0.15)
				)
				(justify mirror)
			)
		)
		(property "Manufacturer" "Nexperia"
			(at 0 0 90)
			(unlocked yes)
			(layer "B.Fab")
			(hide yes)
			(effects
				(font
					(size 1 1)
					(thickness 0.15)
				)
				(justify mirror)
			)
		)
		(property "Author" "Antmicro"
			(at 0 0 90)
			(unlocked yes)
			(layer "B.Fab")
			(hide yes)
			(effects
				(font
					(size 1 1)
					(thickness 0.15)
				)
				(justify mirror)
			)
		)
		(property "License" "Apache-2.0"
			(at 0 0 90)
			(unlocked yes)
			(layer "B.Fab")
			(hide yes)
			(effects
				(font
					(size 1 1)
					(thickness 0.15)
				)
				(justify mirror)
			)
		)
		(sheetname "/HDMI + SD Card/")
		(sheetfile "hdmi-sd-card.kicad_sch")
		(attr smd)
		(fp_line
			(start -0.3 -1)
			(end 0.627 -1.001)
			(stroke
				(width 0.15)
				(type solid)
			)
			(layer "B.SilkS")
		)
		(fp_line
			(start 0.627 -0.6)
			(end 0.627 -1.001)
			(stroke
				(width 0.15)
				(type solid)
			)
			(layer "B.SilkS")
		)
		(fp_line
			(start 0.627 0.6)
			(end 0.627 0.999)
			(stroke
				(width 0.15)
				(type solid)
			)
			(layer "B.SilkS")
		)
		(fp_line
			(start -0.3 1)
			(end 0.627 0.999)
			(stroke
				(width 0.15)
				(type solid)
			)
			(layer "B.SilkS")
		)
		(fp_line
			(start 0.9 -1.3)
			(end -0.9 -1.3)
			(stroke
				(width 0.05)
				(type solid)
			)
			(layer "B.CrtYd")
		)
		(fp_line
			(start -0.9 -1.3)
			(end -0.9 -1)
			(stroke
				(width 0.05)
				(type solid)
			)
			(layer "B.CrtYd")
		)
		(fp_line
			(start -0.9 -1)
			(end -1.4 -1)
			(stroke
				(width 0.05)
				(type solid)
			)
			(layer "B.CrtYd")
		)
		(fp_line
			(start -1.4 -1)
			(end -1.4 1)
			(stroke
				(width 0.05)
				(type solid)
			)
			(layer "B.CrtYd")
		)
		(fp_line
			(start 1.4 -0.4)
			(end 0.9 -0.4)
			(stroke
				(width 0.05)
				(type solid)
			)
			(layer "B.CrtYd")
		)
		(fp_line
			(start 0.9 -0.4)
			(end 0.9 -1.3)
			(stroke
				(width 0.05)
				(type solid)
			)
			(layer "B.CrtYd")
		)
		(fp_line
			(start 1.4 0.4)
			(end 1.4 -0.4)
			(stroke
				(width 0.05)
				(type solid)
			)
			(layer "B.CrtYd")
		)
		(fp_line
			(start 0.9 0.4)
			(end 1.4 0.4)
			(stroke
				(width 0.05)
				(type solid)
			)
			(layer "B.CrtYd")
		)
		(fp_line
			(start -0.9 1)
			(end -1.4 1)
			(stroke
				(width 0.05)
				(type solid)
			)
			(layer "B.CrtYd")
		)
		(fp_line
			(start 0.9 1.3)
			(end 0.9 0.4)
			(stroke
				(width 0.05)
				(type solid)
			)
			(layer "B.CrtYd")
		)
		(fp_line
			(start -0.9 1.3)
			(end -0.9 1)
			(stroke
				(width 0.05)
				(type solid)
			)
			(layer "B.CrtYd")
		)
		(fp_line
			(start -0.9 1.3)
			(end 0.9 1.3)
			(stroke
				(width 0.05)
				(type solid)
			)
			(layer "B.CrtYd")
		)
		(fp_rect
			(start -0.623 0.999)
			(end 0.627 -1.001)
			(stroke
				(width 0.15)
				(type solid)
			)
			(fill no)
			(layer "B.Fab")
		)
		(fp_text user "License: Apache-2.0"
			(at -1.45 -6.782 270)
			(layer "B.Fab")
			(effects
				(font
					(size 0.7 0.7)
					(thickness 0.15)
				)
				(justify left bottom mirror)
			)
		)
		(fp_text user "Author: Antmicro"
			(at -1.45 -5.782 270)
			(layer "B.Fab")
			(effects
				(font
					(size 0.7 0.7)
					(thickness 0.15)
				)
				(justify left bottom mirror)
			)
		)
		(fp_text user "${REFERENCE}"
			(at -1.45 -4.783 270)
			(layer "B.Fab")
			(effects
				(font
					(size 0.7 0.7)
					(thickness 0.15)
				)
				(justify left bottom mirror)
			)
		)
		(pad "1" smd rect
			(at -1.051 0.65)
			(size 0.6 0.6)
			(layers "B.Cu" "B.Mask" "B.Paste")
			(net 500 "HDMI_IN_HPD")
			(pinfunction "G")
			(pintype "passive")
		)
		(pad "2" smd rect
			(at -1.051 -0.65)
			(size 0.6 0.6)
			(layers "B.Cu" "B.Mask" "B.Paste")
			(net 1 "GND")
			(pinfunction "S")
			(pintype "passive")
		)
		(pad "3" smd rect
			(at 1.05 0)
			(size 0.6 0.6)
			(layers "B.Cu" "B.Mask" "B.Paste")
			(net 506 "Net-(Q18-G)")
			(pinfunction "D")
			(pintype "passive")
		)
	)
	(footprint "antmicro-footprints:C_0402_1005Metric_EIA"
		(layer "B.Cu")
		(at 184 148.5 90)
		(descr "Capacitor SMD 0402 (1005 Metric), square (rectangular) end terminal, IPC_7351 nominal, (Body size source: IPC-SM-782 page 76, https://www.pcb-3d.com/wordpress/wp-content/uploads/ipc-sm-782a_amendment_1_and_2.pdf)")
		(tags "capacitor 0402")
		(property "Reference" "C34"
			(at 11.925 -30.675 270)
			(layer "B.SilkS")
			(effects
				(font
					(size 0.7 0.7)
					(thickness 0.15)
				)
				(justify left bottom mirror)
			)
		)
		(property "Value" "C_1u_25V_0402"
			(at 0 -1.169 270)
			(layer "B.Fab")
			(effects
				(font
					(size 0.7 0.7)
					(thickness 0.15)
				)
				(justify left bottom mirror)
			)
		)
		(property "Datasheet" "https://www.murata.com/products/productdetail?partno=GRM155R61E105KE11%23"
			(at 0 0 90)
			(layer "F.Fab")
			(hide yes)
			(effects
				(font
					(size 1.27 1.27)
					(thickness 0.15)
				)
			)
		)
		(property "MPN" "GRM155R61E105KE11J"
			(at 0 0 90)
			(unlocked yes)
			(layer "B.Fab")
			(hide yes)
			(effects
				(font
					(size 1 1)
					(thickness 0.15)
				)
				(justify mirror)
			)
		)
		(property "Manufacturer" "Murata"
			(at 0 0 90)
			(unlocked yes)
			(layer "B.Fab")
			(hide yes)
			(effects
				(font
					(size 1 1)
					(thickness 0.15)
				)
				(justify mirror)
			)
		)
		(property "License" "Apache-2.0"
			(at 0 0 90)
			(unlocked yes)
			(layer "B.Fab")
			(hide yes)
			(effects
				(font
					(size 1 1)
					(thickness 0.15)
				)
				(justify mirror)
			)
		)
		(property "Author" "Antmicro"
			(at 0 0 90)
			(unlocked yes)
			(layer "B.Fab")
			(hide yes)
			(effects
				(font
					(size 1 1)
					(thickness 0.15)
				)
				(justify mirror)
			)
		)
		(property "Val" "1u"
			(at 0 0 90)
			(unlocked yes)
			(layer "B.Fab")
			(hide yes)
			(effects
				(font
					(size 1 1)
					(thickness 0.15)
				)
				(justify mirror)
			)
		)
		(property "Voltage" "25V"
			(at 0 0 90)
			(unlocked yes)
			(layer "B.Fab")
			(hide yes)
			(effects
				(font
					(size 1 1)
					(thickness 0.15)
				)
				(justify mirror)
			)
		)
		(property "Dielectric" "X5R"
			(at 0 0 90)
			(unlocked yes)
			(layer "B.Fab")
			(hide yes)
			(effects
				(font
					(size 1 1)
					(thickness 0.15)
				)
				(justify mirror)
			)
		)
		(sheetname "/FPGA power/")
		(sheetfile "fpga-power.kicad_sch")
		(attr smd)
		(fp_rect
			(start -0.95 0.45)
			(end 0.95 -0.45)
			(stroke
				(width 0.05)
				(type default)
			)
			(fill no)
			(layer "B.CrtYd")
		)
		(fp_line
			(start 0.498 -0.248)
			(end -0.5 -0.248)
			(stroke
				(width 0.15)
				(type solid)
			)
			(layer "B.Fab")
		)
		(fp_line
			(start -0.5 -0.248)
			(end -0.5 0.25)
			(stroke
				(width 0.15)
				(type solid)
			)
			(layer "B.Fab")
		)
		(fp_line
			(start 0.498 0.25)
			(end 0.498 -0.248)
			(stroke
				(width 0.15)
				(type solid)
			)
			(layer "B.Fab")
		)
		(fp_line
			(start -0.5 0.25)
			(end 0.498 0.25)
			(stroke
				(width 0.15)
				(type solid)
			)
			(layer "B.Fab")
		)
		(fp_text user "Author: Antmicro"
			(at -0.9656 -5.569 270)
			(layer "B.Fab")
			(effects
				(font
					(size 0.7 0.7)
					(thickness 0.15)
				)
				(justify left bottom mirror)
			)
		)
		(fp_text user "License: Apache-2.0"
			(at -0.9656 -4.369 270)
			(layer "B.Fab")
			(effects
				(font
					(size 0.7 0.7)
					(thickness 0.15)
				)
				(justify left bottom mirror)
			)
		)
		(fp_text user "${REFERENCE}"
			(at -0.9656 -3.169 270)
			(layer "B.Fab")
			(effects
				(font
					(size 0.7 0.7)
					(thickness 0.15)
				)
				(justify left bottom mirror)
			)
		)
		(pad "1" smd roundrect
			(at -0.5 0)
			(size 0.6 0.6)
			(layers "B.Cu" "B.Mask" "B.Paste")
			(roundrect_rratio 0.25)
			(net 1 "GND")
			(pintype "passive")
		)
		(pad "2" smd roundrect
			(at 0.498 0 90)
			(size 0.6 0.6)
			(layers "B.Cu" "B.Mask" "B.Paste")
			(roundrect_rratio 0.25)
			(net 553 "+0V85")
			(pintype "passive")
		)
	)
	(footprint "antmicro-footprints:R_0402_1005Metric"
		(layer "B.Cu")
		(at 250.03 117.11 180)
		(descr "Resistor SMD 0402")
		(tags "resistor SMD 0402")
		(property "Reference" "R238"
			(at -1.37 0.57 0)
			(layer "B.SilkS")
			(effects
				(font
					(size 0.7 0.7)
					(thickness 0.15)
				)
				(justify left bottom mirror)
			)
		)
		(property "Value" "R_47k_0402"
			(at -1.011843 -1.772047 0)
			(layer "B.Fab")
			(effects
				(font
					(size 0.7 0.7)
					(thickness 0.15)
				)
				(justify left bottom mirror)
			)
		)
		(property "Datasheet" "https://www.bourns.com/docs/product-datasheets/cr.pdf"
			(at 0 0 180)
			(layer "F.Fab")
			(hide yes)
			(effects
				(font
					(size 1.27 1.27)
					(thickness 0.15)
				)
			)
		)
		(property "MPN" "CR0402-FX-4702GLF"
			(at 0 0 180)
			(unlocked yes)
			(layer "B.Fab")
			(hide yes)
			(effects
				(font
					(size 1 1)
					(thickness 0.15)
				)
				(justify mirror)
			)
		)
		(property "Manufacturer" "Bourns"
			(at 0 0 180)
			(unlocked yes)
			(layer "B.Fab")
			(hide yes)
			(effects
				(font
					(size 1 1)
					(thickness 0.15)
				)
				(justify mirror)
			)
		)
		(property "License" "Apache-2.0"
			(at 0 0 180)
			(unlocked yes)
			(layer "B.Fab")
			(hide yes)
			(effects
				(font
					(size 1 1)
					(thickness 0.15)
				)
				(justify mirror)
			)
		)
		(property "Author" "Antmicro"
			(at 0 0 180)
			(unlocked yes)
			(layer "B.Fab")
			(hide yes)
			(effects
				(font
					(size 1 1)
					(thickness 0.15)
				)
				(justify mirror)
			)
		)
		(property "Val" "47k"
			(at 0 0 180)
			(unlocked yes)
			(layer "B.Fab")
			(hide yes)
			(effects
				(font
					(size 1 1)
					(thickness 0.15)
				)
				(justify mirror)
			)
		)
		(property "Tolerance" "1%"
			(at 0 0 180)
			(unlocked yes)
			(layer "B.Fab")
			(hide yes)
			(effects
				(font
					(size 1 1)
					(thickness 0.15)
				)
				(justify mirror)
			)
		)
		(sheetname "/DDR5 RDIMM/")
		(sheetfile "ddr5-rdimm.kicad_sch")
		(attr smd)
		(fp_rect
			(start -0.925 0.47)
			(end 0.925 -0.47)
			(stroke
				(width 0.05)
				(type default)
			)
			(fill no)
			(layer "B.CrtYd")
		)
		(fp_rect
			(start -0.5 0.25)
			(end 0.5 -0.25)
			(stroke
				(width 0.15)
				(type solid)
			)
			(fill no)
			(layer "B.Fab")
		)
		(fp_text user "Author: Antmicro"
			(at -0.95 -4.169 0)
			(layer "B.Fab")
			(effects
				(font
					(size 0.7 0.7)
					(thickness 0.15)
				)
				(justify left bottom mirror)
			)
		)
		(fp_text user "${REFERENCE}"
			(at -0.95 -3.168 0)
			(layer "B.Fab")
			(effects
				(font
					(size 0.7 0.7)
					(thickness 0.15)
				)
				(justify left bottom mirror)
			)
		)
		(fp_text user "License: Apache-2.0"
			(at -0.95 -5.169 0)
			(layer "B.Fab")
			(effects
				(font
					(size 0.7 0.7)
					(thickness 0.15)
				)
				(justify left bottom mirror)
			)
		)
		(pad "1" smd roundrect
			(at -0.48 0 180)
			(size 0.59 0.64)
			(layers "B.Cu" "B.Mask" "B.Paste")
			(roundrect_rratio 0.25)
			(net 806 "Net-(Q23-G)")
			(pintype "passive")
		)
		(pad "2" smd roundrect
			(at 0.48 0 180)
			(size 0.59 0.64)
			(layers "B.Cu" "B.Mask" "B.Paste")
			(roundrect_rratio 0.25)
			(net 35 "VDC")
			(pintype "passive")
		)
	)
)
